(kicad_pcb
	(version 20260206)
	(generator "pcbnew")
	(generator_version "10.0")
	(general
		(thickness 1.6)
		(legacy_teardrops no)
	)
	(paper "A4")
	(title_block
		(title "Bryce Canyon_IOM_M2_16342-2_OCP.brd")
		(comment 1 "Bryce Canyon / footprints 283-289 of 1146")
	)
	(layers
		(0 "F.Cu" signal "TOP")
		(4 "In1.Cu" signal "L2GND")
		(6 "In2.Cu" signal "L3")
		(8 "In3.Cu" signal "L4VCC")
		(10 "In4.Cu" signal "L5VCC")
		(12 "In5.Cu" signal "L6")
		(14 "In6.Cu" signal "L7GND")
		(2 "B.Cu" signal "BOTTOM")
		(9 "F.Adhes" user "F.Adhesive")
		(11 "B.Adhes" user "B.Adhesive")
		(13 "F.Paste" user "Package Geometry/Pastemask Top")
		(15 "B.Paste" user "Package Geometry/Pastemask Bottom")
		(5 "F.SilkS" user "Ref Des/Silkscreen Top")
		(7 "B.SilkS" user "Ref Des/Silkscreen Bottom")
		(1 "F.Mask" user "Board Geometry/Soldermask Top")
		(3 "B.Mask" user "Board Geometry/Soldermask Bottom")
		(17 "Dwgs.User" user "User.Drawings")
		(19 "Cmts.User" user "User.Comments")
		(21 "Eco1.User" user "User.Eco1")
		(23 "Eco2.User" user "User.Eco2")
		(25 "Edge.Cuts" user "Board Geometry/Outline")
		(27 "Margin" user)
		(31 "F.CrtYd" user "Package Geometry/Place Bound Top")
		(29 "B.CrtYd" user "Package Geometry/Place Bound Bottom")
		(35 "F.Fab" user "Ref Des/Assembly Top")
		(33 "B.Fab" user "Ref Des/Assembly Bottom")
	)
	(footprint ""
		(layer "F.Cu")
		(at 24.452072 -15.81277 -90)
		(property "Reference" "C528"
			(at 0 0 270)
			(layer "F.SilkS")
			(hide yes)
			(effects
				(font
					(size 1.27 1.27)
				)
			)
		)
		(property "Value" "SC1000P2KV6KX-GP-U"
			(at 0.0508 -3.5052 270)
			(unlocked yes)
			(layer "F.Fab")
			(hide yes)
			(effects
				(font
					(size 1.016 1.016)
					(thickness 0.1524)
				)
			)
		)
		(property "Device Type" "C1206H58"
			(at 0.0508 -5.0292 270)
			(unlocked yes)
			(layer "F.Fab")
			(hide yes)
			(effects
				(font
					(size 1.016 1.016)
					(thickness 0.1524)
				)
			)
		)
		(duplicate_pad_numbers_are_jumpers no)
		(fp_line
			(start -1.016 2.2352)
			(end -1.016 0.8128)
			(stroke
				(width 0.1524)
				(type default)
			)
			(layer "F.SilkS")
		)
		(fp_line
			(start 1.016 2.2352)
			(end -1.016 2.2352)
			(stroke
				(width 0.1524)
				(type default)
			)
			(layer "F.SilkS")
		)
		(fp_line
			(start 1.016 0.8382)
			(end 1.016 2.2352)
			(stroke
				(width 0.1524)
				(type default)
			)
			(layer "F.SilkS")
		)
		(fp_line
			(start -1.016 -2.2352)
			(end -1.016 -0.8382)
			(stroke
				(width 0.1524)
				(type default)
			)
			(layer "F.SilkS")
		)
		(fp_line
			(start 1.016 -2.2352)
			(end 1.016 -0.8382)
			(stroke
				(width 0.1524)
				(type default)
			)
			(layer "F.SilkS")
		)
		(fp_line
			(start 1.016 -2.2352)
			(end -1.016 -2.2352)
			(stroke
				(width 0.1524)
				(type default)
			)
			(layer "F.SilkS")
		)
		(fp_rect
			(start -1.0922 2.3114)
			(end 1.0922 -2.3114)
			(stroke
				(width 0)
				(type default)
			)
			(fill no)
			(layer "F.CrtYd")
		)
		(fp_poly
			(pts
				(xy -1.0922 -2.3114) (xy 1.0922 -2.3114) (xy 1.0922 2.3114) (xy -1.0922 2.3114)
			)
			(stroke
				(width 0)
				(type default)
			)
			(fill no)
			(layer "F.Fab")
		)
		(pad "1" smd rect
			(at 0 -1.397 270)
			(size 1.651 1.27)
			(layers "F.Cu" "F.Mask" "F.Paste")
			(net "PWR_BTN_GND")
		)
		(pad "2" smd rect
			(at 0 1.397 270)
			(size 1.651 1.27)
			(layers "F.Cu" "F.Mask" "F.Paste")
			(net "GND")
		)
	)
	(footprint ""
		(layer "F.Cu")
		(at 68.6054 -124.333 -90)
		(property "Reference" "R267"
			(at 0 0 270)
			(layer "F.SilkS")
			(hide yes)
			(effects
				(font
					(size 1.27 1.27)
				)
			)
		)
		(property "Value" "2K2R2J-2-GP"
			(at 0.064008 -3.993896 270)
			(unlocked yes)
			(layer "F.Fab")
			(hide yes)
			(effects
				(font
					(size 1.016 1.016)
					(thickness 0.1524)
				)
			)
		)
		(property "Device Type" "R402H16"
			(at 0.064008 -5.517896 270)
			(unlocked yes)
			(layer "F.Fab")
			(hide yes)
			(effects
				(font
					(size 1.016 1.016)
					(thickness 0.1524)
				)
			)
		)
		(duplicate_pad_numbers_are_jumpers no)
		(fp_line
			(start -0.508 -0.9398)
			(end -0.508 0.9398)
			(stroke
				(width 0.1524)
				(type default)
			)
			(layer "F.SilkS")
		)
		(fp_line
			(start 0.508 -0.9398)
			(end -0.508 -0.9398)
			(stroke
				(width 0.1524)
				(type default)
			)
			(layer "F.SilkS")
		)
		(fp_rect
			(start -0.508 0.9398)
			(end 0.508 -0.9398)
			(stroke
				(width 0)
				(type default)
			)
			(fill no)
			(layer "F.CrtYd")
		)
		(fp_rect
			(start -0.508 0.9398)
			(end 0.508 -0.9398)
			(stroke
				(width 0)
				(type default)
			)
			(fill no)
			(layer "F.Fab")
		)
		(pad "1" smd custom
			(at 0 -0.4445 270)
			(size 0.1397 0.1397)
			(layers "F.Cu" "F.Mask" "F.Paste")
			(net "P3V3_STBY")
			(options
				(clearance outline)
				(anchor circle)
			)
			(primitives
				(gr_poly
					(pts
						(arc
							(start -0.1778 -0.2794)
							(mid -0.249642 -0.249642)
							(end -0.2794 -0.1778)
						)
						(arc
							(start -0.2794 0.1778)
							(mid -0.249642 0.249642)
							(end -0.1778 0.2794)
						)
						(arc
							(start 0.1778 0.2794)
							(mid 0.249642 0.249642)
							(end 0.2794 0.1778)
						)
						(arc
							(start 0.2794 -0.1778)
							(mid 0.249642 -0.249642)
							(end 0.1778 -0.2794)
						)
					)
					(width 0)
					(fill yes)
				)
			)
		)
		(pad "2" smd custom
			(at 0 0.4445 270)
			(size 0.1397 0.1397)
			(layers "F.Cu" "F.Mask" "F.Paste")
			(net "FLA_CS_1_R")
			(options
				(clearance outline)
				(anchor circle)
			)
			(primitives
				(gr_poly
					(pts
						(arc
							(start -0.1778 -0.2794)
							(mid -0.249642 -0.249642)
							(end -0.2794 -0.1778)
						)
						(arc
							(start -0.2794 0.1778)
							(mid -0.249642 0.249642)
							(end -0.1778 0.2794)
						)
						(arc
							(start 0.1778 0.2794)
							(mid 0.249642 0.249642)
							(end 0.2794 0.1778)
						)
						(arc
							(start 0.2794 -0.1778)
							(mid 0.249642 -0.249642)
							(end 0.1778 -0.2794)
						)
					)
					(width 0)
					(fill yes)
				)
			)
		)
	)
	(footprint ""
		(layer "F.Cu")
		(at 16.041116 -162.5473 -90)
		(property "Reference" "R530"
			(at 0 0 270)
			(layer "F.SilkS")
			(hide yes)
			(effects
				(font
					(size 1.27 1.27)
				)
			)
		)
		(property "Value" "2K49R2F-GP"
			(at 0.064008 -3.993896 270)
			(unlocked yes)
			(layer "F.Fab")
			(hide yes)
			(effects
				(font
					(size 1.016 1.016)
					(thickness 0.1524)
				)
			)
		)
		(property "Device Type" "R402H16"
			(at 0.064008 -5.517896 270)
			(unlocked yes)
			(layer "F.Fab")
			(hide yes)
			(effects
				(font
					(size 1.016 1.016)
					(thickness 0.1524)
				)
			)
		)
		(duplicate_pad_numbers_are_jumpers no)
		(fp_line
			(start -0.508 -0.9398)
			(end -0.508 0.9398)
			(stroke
				(width 0.1524)
				(type default)
			)
			(layer "F.SilkS")
		)
		(fp_line
			(start 0.508 -0.9398)
			(end -0.508 -0.9398)
			(stroke
				(width 0.1524)
				(type default)
			)
			(layer "F.SilkS")
		)
		(fp_rect
			(start -0.508 0.9398)
			(end 0.508 -0.9398)
			(stroke
				(width 0)
				(type default)
			)
			(fill no)
			(layer "F.CrtYd")
		)
		(fp_rect
			(start -0.508 0.9398)
			(end 0.508 -0.9398)
			(stroke
				(width 0)
				(type default)
			)
			(fill no)
			(layer "F.Fab")
		)
		(pad "1" smd custom
			(at 0 -0.4445 270)
			(size 0.1397 0.1397)
			(layers "F.Cu" "F.Mask" "F.Paste")
			(net "TPS74801_P1V2_STBY_OUT")
			(options
				(clearance outline)
				(anchor circle)
			)
			(primitives
				(gr_poly
					(pts
						(arc
							(start -0.1778 -0.2794)
							(mid -0.249642 -0.249642)
							(end -0.2794 -0.1778)
						)
						(arc
							(start -0.2794 0.1778)
							(mid -0.249642 0.249642)
							(end -0.1778 0.2794)
						)
						(arc
							(start 0.1778 0.2794)
							(mid 0.249642 0.249642)
							(end 0.2794 0.1778)
						)
						(arc
							(start 0.2794 -0.1778)
							(mid 0.249642 -0.249642)
							(end 0.1778 -0.2794)
						)
					)
					(width 0)
					(fill yes)
				)
			)
		)
		(pad "2" smd custom
			(at 0 0.4445 270)
			(size 0.1397 0.1397)
			(layers "F.Cu" "F.Mask" "F.Paste")
			(net "TPS74801_P1V2_STBY_FB")
			(options
				(clearance outline)
				(anchor circle)
			)
			(primitives
				(gr_poly
					(pts
						(arc
							(start -0.1778 -0.2794)
							(mid -0.249642 -0.249642)
							(end -0.2794 -0.1778)
						)
						(arc
							(start -0.2794 0.1778)
							(mid -0.249642 0.249642)
							(end -0.1778 0.2794)
						)
						(arc
							(start 0.1778 0.2794)
							(mid 0.249642 0.249642)
							(end 0.2794 0.1778)
						)
						(arc
							(start 0.2794 -0.1778)
							(mid 0.249642 -0.249642)
							(end 0.1778 -0.2794)
						)
					)
					(width 0)
					(fill yes)
				)
			)
		)
	)
	(footprint ""
		(layer "F.Cu")
		(at 112.86109 -8.726678 -90)
		(property "Reference" "C131"
			(at 0 0 270)
			(layer "F.SilkS")
			(hide yes)
			(effects
				(font
					(size 1.27 1.27)
				)
			)
		)
		(property "Value" "SCD01U25V2KX-3GP"
			(at 1.1811 -2.7051 270)
			(unlocked yes)
			(layer "F.Fab")
			(hide yes)
			(effects
				(font
					(size 1.016 1.016)
					(thickness 0.1524)
				)
			)
		)
		(property "Device Type" "C402H22"
			(at 1.1811 -4.2291 270)
			(unlocked yes)
			(layer "F.Fab")
			(hide yes)
			(effects
				(font
					(size 1.016 1.016)
					(thickness 0.1524)
				)
			)
		)
		(duplicate_pad_numbers_are_jumpers no)
		(fp_rect
			(start -0.4318 0.9525)
			(end 0.4318 -0.9525)
			(stroke
				(width 0)
				(type default)
			)
			(fill no)
			(layer "F.CrtYd")
		)
		(fp_rect
			(start -0.4318 0.9525)
			(end 0.4318 -0.9525)
			(stroke
				(width 0)
				(type default)
			)
			(fill no)
			(layer "F.Fab")
		)
		(pad "1" smd custom
			(at 0 -0.4445 270)
			(size 0.1524 0.1524)
			(layers "F.Cu" "F.Mask" "F.Paste")
			(net "MB0_TIME_R")
			(options
				(clearance outline)
				(anchor circle)
			)
			(primitives
				(gr_poly
					(pts
						(arc
							(start 0.3048 -0.2032)
							(mid 0.275042 -0.275042)
							(end 0.2032 -0.3048)
						)
						(arc
							(start -0.2032 -0.3048)
							(mid -0.275042 -0.275042)
							(end -0.3048 -0.2032)
						)
						(arc
							(start -0.3048 0.2032)
							(mid -0.275042 0.275042)
							(end -0.2032 0.3048)
						)
						(arc
							(start 0.2032 0.3048)
							(mid 0.275042 0.275042)
							(end 0.3048 0.2032)
						)
					)
					(width 0)
					(fill yes)
				)
			)
		)
		(pad "2" smd custom
			(at 0 0.4445 270)
			(size 0.1524 0.1524)
			(layers "F.Cu" "F.Mask" "F.Paste")
			(net "AGND_CURRENT_MON")
			(options
				(clearance outline)
				(anchor circle)
			)
			(primitives
				(gr_poly
					(pts
						(arc
							(start 0.3048 -0.2032)
							(mid 0.275042 -0.275042)
							(end 0.2032 -0.3048)
						)
						(arc
							(start -0.2032 -0.3048)
							(mid -0.275042 -0.275042)
							(end -0.3048 -0.2032)
						)
						(arc
							(start -0.3048 0.2032)
							(mid -0.275042 0.275042)
							(end -0.2032 0.3048)
						)
						(arc
							(start 0.2032 0.3048)
							(mid 0.275042 0.275042)
							(end 0.3048 0.2032)
						)
					)
					(width 0)
					(fill yes)
				)
			)
		)
	)
	(footprint ""
		(layer "F.Cu")
		(at 48.4124 -131.4958 180)
		(property "Reference" "R177"
			(at 0 0 180)
			(layer "F.SilkS")
			(hide yes)
			(effects
				(font
					(size 1.27 1.27)
				)
			)
		)
		(property "Value" "0R2J-2-GP"
			(at 0.064008 -3.993896 180)
			(unlocked yes)
			(layer "F.Fab")
			(hide yes)
			(effects
				(font
					(size 1.016 1.016)
					(thickness 0.1524)
				)
			)
		)
		(property "Device Type" "R402H16"
			(at 0.064008 -5.517896 180)
			(unlocked yes)
			(layer "F.Fab")
			(hide yes)
			(effects
				(font
					(size 1.016 1.016)
					(thickness 0.1524)
				)
			)
		)
		(duplicate_pad_numbers_are_jumpers no)
		(fp_line
			(start 0.508 -0.9398)
			(end -0.508 -0.9398)
			(stroke
				(width 0.1524)
				(type default)
			)
			(layer "F.SilkS")
		)
		(fp_line
			(start -0.508 -0.9398)
			(end -0.508 0.9398)
			(stroke
				(width 0.1524)
				(type default)
			)
			(layer "F.SilkS")
		)
		(fp_rect
			(start -0.508 0.9398)
			(end 0.508 -0.9398)
			(stroke
				(width 0)
				(type default)
			)
			(fill no)
			(layer "F.CrtYd")
		)
		(fp_rect
			(start -0.508 0.9398)
			(end 0.508 -0.9398)
			(stroke
				(width 0)
				(type default)
			)
			(fill no)
			(layer "F.Fab")
		)
		(pad "1" smd custom
			(at 0 -0.4445 180)
			(size 0.1397 0.1397)
			(layers "F.Cu" "F.Mask" "F.Paste")
			(net "I2C_TPM_SCL")
			(options
				(clearance outline)
				(anchor circle)
			)
			(primitives
				(gr_poly
					(pts
						(arc
							(start -0.1778 -0.2794)
							(mid -0.249642 -0.249642)
							(end -0.2794 -0.1778)
						)
						(arc
							(start -0.2794 0.1778)
							(mid -0.249642 0.249642)
							(end -0.1778 0.2794)
						)
						(arc
							(start 0.1778 0.2794)
							(mid 0.249642 0.249642)
							(end 0.2794 0.1778)
						)
						(arc
							(start 0.2794 -0.1778)
							(mid 0.249642 -0.249642)
							(end 0.1778 -0.2794)
						)
					)
					(width 0)
					(fill yes)
				)
			)
		)
		(pad "2" smd custom
			(at 0 0.4445 180)
			(size 0.1397 0.1397)
			(layers "F.Cu" "F.Mask" "F.Paste")
			(net "BMC_SMB14_CLK")
			(options
				(clearance outline)
				(anchor circle)
			)
			(primitives
				(gr_poly
					(pts
						(arc
							(start -0.1778 -0.2794)
							(mid -0.249642 -0.249642)
							(end -0.2794 -0.1778)
						)
						(arc
							(start -0.2794 0.1778)
							(mid -0.249642 0.249642)
							(end -0.1778 0.2794)
						)
						(arc
							(start 0.1778 0.2794)
							(mid 0.249642 0.249642)
							(end 0.2794 0.1778)
						)
						(arc
							(start 0.2794 -0.1778)
							(mid 0.249642 -0.249642)
							(end 0.1778 -0.2794)
						)
					)
					(width 0)
					(fill yes)
				)
			)
		)
	)
	(footprint ""
		(layer "F.Cu")
		(at 224.968054 -71.934832 90)
		(property "Reference" "C658"
			(at 0 0 90)
			(layer "F.SilkS")
			(hide yes)
			(effects
				(font
					(size 1.27 1.27)
				)
			)
		)
		(property "Value" "ST100U6D3VDM-8-GP"
			(at 0 -9.6012 90)
			(unlocked yes)
			(layer "F.Fab")
			(hide yes)
			(effects
				(font
					(size 1.016 1.016)
					(thickness 0.1524)
				)
			)
		)
		(property "Device Type" "CT7343H83"
			(at 0 -11.1252 90)
			(unlocked yes)
			(layer "F.Fab")
			(hide yes)
			(effects
				(font
					(size 1.016 1.016)
					(thickness 0.1524)
				)
			)
		)
		(duplicate_pad_numbers_are_jumpers no)
		(fp_line
			(start 2.286 -4.8768)
			(end -2.286 -4.8768)
			(stroke
				(width 0.1524)
				(type default)
			)
			(layer "F.SilkS")
		)
		(fp_line
			(start -2.286 -4.8768)
			(end -2.286 -2.032)
			(stroke
				(width 0.1524)
				(type default)
			)
			(layer "F.SilkS")
		)
		(fp_line
			(start 2.1082 -4.699)
			(end -2.1082 -4.699)
			(stroke
				(width 0.508)
				(type default)
			)
			(layer "F.SilkS")
		)
		(fp_line
			(start 2.286 -2.032)
			(end 2.286 -4.8768)
			(stroke
				(width 0.1524)
				(type default)
			)
			(layer "F.SilkS")
		)
		(fp_line
			(start 2.286 2.032)
			(end 2.286 4.8768)
			(stroke
				(width 0.1524)
				(type default)
			)
			(layer "F.SilkS")
		)
		(fp_line
			(start 2.286 4.8768)
			(end -2.286 4.8768)
			(stroke
				(width 0.1524)
				(type default)
			)
			(layer "F.SilkS")
		)
		(fp_line
			(start -2.286 4.8768)
			(end -2.286 2.032)
			(stroke
				(width 0.1524)
				(type default)
			)
			(layer "F.SilkS")
		)
		(fp_rect
			(start -2.1463 3.6449)
			(end 2.1463 -3.6449)
			(stroke
				(width 0)
				(type default)
			)
			(fill no)
			(layer "F.CrtYd")
		)
		(fp_poly
			(pts
				(xy -2.54 4.953) (xy -2.54 4.2926) (xy -3.81 4.2926) (xy -3.81 -4.2926) (xy -2.54 -4.2926) (xy -2.54 -4.953)
				(xy 2.54 -4.953) (xy 2.54 -4.2926) (xy 3.81 -4.2926) (xy 3.81 -1.6256) (xy 2.1463 -1.6256) (xy 2.1463 -3.6449)
				(xy -2.1463 -3.6449) (xy -2.1463 3.6449) (xy 2.1463 3.6449) (xy 2.1463 -1.6129) (xy 3.81 -1.6129)
				(xy 3.81 4.2926) (xy 2.54 4.2926) (xy 2.54 4.953)
			)
			(stroke
				(width 0)
				(type default)
			)
			(fill no)
			(layer "F.CrtYd")
		)
		(fp_rect
			(start 2.54 4.2926)
			(end 3.81 -4.2926)
			(stroke
				(width 0)
				(type default)
			)
			(fill no)
			(layer "F.Fab")
		)
		(fp_rect
			(start -3.81 4.2926)
			(end -2.54 -4.2926)
			(stroke
				(width 0)
				(type default)
			)
			(fill no)
			(layer "F.Fab")
		)
		(fp_rect
			(start -2.54 4.953)
			(end 2.54 -4.953)
			(stroke
				(width 0)
				(type default)
			)
			(fill no)
			(layer "F.Fab")
		)
		(pad "1" smd rect
			(at 0 -3.1496 90)
			(size 2.413 2.286)
			(layers "F.Cu" "F.Mask" "F.Paste")
			(net "P3V3_M2")
		)
		(pad "2" smd rect
			(at 0 3.1496 90)
			(size 2.413 2.286)
			(layers "F.Cu" "F.Mask" "F.Paste")
			(net "GND")
		)
		(zone
			(layer "F.Cu")
			(hatch none 0.5)
			(connect_pads
				(clearance 0)
			)
			(min_thickness 0.25)
			(keepout
				(tracks allowed)
				(vias not_allowed)
				(pads allowed)
				(copperpour not_allowed)
				(footprints allowed)
			)
			(placement
				(enabled no)
				(sheetname "")
			)
			(fill
				(thermal_gap 0.5)
				(thermal_bridge_width 0.5)
				(island_removal_mode 0)
			)
			(polygon
				(pts
					(xy 223.278954 -73.446132) (xy 220.370654 -73.446132) (xy 220.370654 -70.423532) (xy 223.266254 -70.423532)
					(xy 223.596454 -70.423532) (xy 223.596454 -73.446132)
				)
			)
		)
		(zone
			(layer "F.Cu")
			(hatch none 0.5)
			(connect_pads
				(clearance 0)
			)
			(min_thickness 0.25)
			(keepout
				(tracks allowed)
				(vias not_allowed)
				(pads allowed)
				(copperpour not_allowed)
				(footprints allowed)
			)
			(placement
				(enabled no)
				(sheetname "")
			)
			(fill
				(thermal_gap 0.5)
				(thermal_bridge_width 0.5)
				(island_removal_mode 0)
			)
			(polygon
				(pts
					(xy 229.565454 -70.423532) (xy 229.565454 -73.446132) (xy 226.669854 -73.446132) (xy 226.339654 -73.446132)
					(xy 226.339654 -70.423532) (xy 226.669854 -70.423532)
				)
			)
		)
	)
	(footprint ""
		(layer "F.Cu")
		(at 24.579072 -14.03477 -90)
		(property "Reference" "R45"
			(at 0 0 270)
			(layer "F.SilkS")
			(hide yes)
			(effects
				(font
					(size 1.27 1.27)
				)
			)
		)
		(property "Value" "1MR2F-GP"
			(at 0.064008 -3.993896 270)
			(unlocked yes)
			(layer "F.Fab")
			(hide yes)
			(effects
				(font
					(size 1.016 1.016)
					(thickness 0.1524)
				)
			)
		)
		(property "Device Type" "R402H16"
			(at 0.064008 -5.517896 270)
			(unlocked yes)
			(layer "F.Fab")
			(hide yes)
			(effects
				(font
					(size 1.016 1.016)
					(thickness 0.1524)
				)
			)
		)
		(duplicate_pad_numbers_are_jumpers no)
		(fp_line
			(start -0.508 -0.9398)
			(end -0.508 0.9398)
			(stroke
				(width 0.1524)
				(type default)
			)
			(layer "F.SilkS")
		)
		(fp_line
			(start 0.508 -0.9398)
			(end -0.508 -0.9398)
			(stroke
				(width 0.1524)
				(type default)
			)
			(layer "F.SilkS")
		)
		(fp_rect
			(start -0.508 0.9398)
			(end 0.508 -0.9398)
			(stroke
				(width 0)
				(type default)
			)
			(fill no)
			(layer "F.CrtYd")
		)
		(fp_rect
			(start -0.508 0.9398)
			(end 0.508 -0.9398)
			(stroke
				(width 0)
				(type default)
			)
			(fill no)
			(layer "F.Fab")
		)
		(pad "1" smd custom
			(at 0 -0.4445 270)
			(size 0.1397 0.1397)
			(layers "F.Cu" "F.Mask" "F.Paste")
			(net "PWR_BTN_GND")
			(options
				(clearance outline)
				(anchor circle)
			)
			(primitives
				(gr_poly
					(pts
						(arc
							(start -0.1778 -0.2794)
							(mid -0.249642 -0.249642)
							(end -0.2794 -0.1778)
						)
						(arc
							(start -0.2794 0.1778)
							(mid -0.249642 0.249642)
							(end -0.1778 0.2794)
						)
						(arc
							(start 0.1778 0.2794)
							(mid 0.249642 0.249642)
							(end 0.2794 0.1778)
						)
						(arc
							(start 0.2794 -0.1778)
							(mid 0.249642 -0.249642)
							(end 0.1778 -0.2794)
						)
					)
					(width 0)
					(fill yes)
				)
			)
		)
		(pad "2" smd custom
			(at 0 0.4445 270)
			(size 0.1397 0.1397)
			(layers "F.Cu" "F.Mask" "F.Paste")
			(net "GND")
			(options
				(clearance outline)
				(anchor circle)
			)
			(primitives
				(gr_poly
					(pts
						(arc
							(start -0.1778 -0.2794)
							(mid -0.249642 -0.249642)
							(end -0.2794 -0.1778)
						)
						(arc
							(start -0.2794 0.1778)
							(mid -0.249642 0.249642)
							(end -0.1778 0.2794)
						)
						(arc
							(start 0.1778 0.2794)
							(mid 0.249642 0.249642)
							(end 0.2794 0.1778)
						)
						(arc
							(start 0.2794 -0.1778)
							(mid 0.249642 -0.249642)
							(end 0.1778 -0.2794)
						)
					)
					(width 0)
					(fill yes)
				)
			)
		)
	)
)
